(kicad_pcb
	(version 20260206)
	(generator "pcbnew")
	(generator_version "10.0")
	(general
		(thickness 1.6)
		(legacy_teardrops no)
	)
	(paper "A4")
	(title_block
		(title "03242023_DA0F0TMBIJ0_F0T_Motherboard_J_brd_V01_OCP.brd")
		(comment 1 "Grand Teton / footprints 4604-4609 of 6105")
	)
	(layers
		(0 "F.Cu" signal "TOP")
		(4 "In1.Cu" signal "GND")
		(6 "In2.Cu" signal "IN1")
		(8 "In3.Cu" signal "GND1")
		(10 "In4.Cu" signal "IN2")
		(12 "In5.Cu" signal "GND2")
		(14 "In6.Cu" signal "IN3")
		(16 "In7.Cu" signal "GND3")
		(18 "In8.Cu" signal "VCC")
		(20 "In9.Cu" signal "VCC1")
		(22 "In10.Cu" signal "GND4")
		(24 "In11.Cu" signal "IN4")
		(26 "In12.Cu" signal "GND5")
		(28 "In13.Cu" signal "IN5")
		(30 "In14.Cu" signal "GND6")
		(32 "In15.Cu" signal "IN6")
		(34 "In16.Cu" signal "GND7")
		(2 "B.Cu" signal "BOTTOM")
		(9 "F.Adhes" user "F.Adhesive")
		(11 "B.Adhes" user "B.Adhesive")
		(13 "F.Paste" user "Package Geometry/Pastemask Top")
		(15 "B.Paste" user "Package Geometry/Pastemask Bottom")
		(5 "F.SilkS" user "Ref Des/Silkscreen Top")
		(7 "B.SilkS" user "Ref Des/Silkscreen Bottom")
		(1 "F.Mask" user "Board Geometry/Soldermask Top")
		(3 "B.Mask" user "Board Geometry/Soldermask Bottom")
		(17 "Dwgs.User" user "User.Drawings")
		(19 "Cmts.User" user "User.Comments")
		(21 "Eco1.User" user "User.Eco1")
		(23 "Eco2.User" user "User.Eco2")
		(25 "Edge.Cuts" user "Board Geometry/Outline")
		(27 "Margin" user)
		(31 "F.CrtYd" user "Package Geometry/Place Bound Top")
		(29 "B.CrtYd" user "Package Geometry/Place Bound Bottom")
		(35 "F.Fab" user "Ref Des/Assembly Top")
		(33 "B.Fab" user "Ref Des/Assembly Bottom")
	)
	(footprint ""
		(layer "B.Cu")
		(at 295.565322 -363.78642 -90)
		(property "Reference" "PR356"
			(at 0 0 90)
			(layer "B.SilkS")
			(hide yes)
			(effects
				(font
					(size 1.27 1.27)
				)
				(justify mirror)
			)
		)
		(property "Value" ""
			(at 0 0 90)
			(layer "B.Fab")
			(effects
				(font
					(size 1.27 1.27)
				)
				(justify mirror)
			)
		)
		(duplicate_pad_numbers_are_jumpers no)
		(fp_line
			(start -0.7874 0.4064)
			(end 0.7874 0.4064)
			(stroke
				(width 0.1524)
				(type default)
			)
			(layer "B.SilkS")
		)
		(fp_line
			(start 0.7874 0.4064)
			(end 0.7874 -0.4064)
			(stroke
				(width 0.1524)
				(type default)
			)
			(layer "B.SilkS")
		)
		(fp_line
			(start -0.7874 -0.4064)
			(end -0.7874 0.4064)
			(stroke
				(width 0.1524)
				(type default)
			)
			(layer "B.SilkS")
		)
		(fp_line
			(start 0.7874 -0.4064)
			(end -0.7874 -0.4064)
			(stroke
				(width 0.1524)
				(type default)
			)
			(layer "B.SilkS")
		)
		(fp_line
			(start -0.67945 0.3048)
			(end -0.120396 0.3048)
			(stroke
				(width 0.1)
				(type default)
			)
			(layer "B.Fab")
		)
		(fp_line
			(start -0.120396 0.3048)
			(end -0.120396 0.2794)
			(stroke
				(width 0.1)
				(type default)
			)
			(layer "B.Fab")
		)
		(fp_line
			(start 0.12065 0.3048)
			(end 0.67945 0.3048)
			(stroke
				(width 0.1)
				(type default)
			)
			(layer "B.Fab")
		)
		(fp_line
			(start 0.67945 0.3048)
			(end 0.67945 -0.305054)
			(stroke
				(width 0.1)
				(type default)
			)
			(layer "B.Fab")
		)
		(fp_line
			(start -0.120396 0.2794)
			(end 0.12065 0.2794)
			(stroke
				(width 0.1)
				(type default)
			)
			(layer "B.Fab")
		)
		(fp_line
			(start 0.12065 0.2794)
			(end 0.12065 0.3048)
			(stroke
				(width 0.1)
				(type default)
			)
			(layer "B.Fab")
		)
		(fp_line
			(start -0.12065 -0.2794)
			(end -0.12065 -0.3048)
			(stroke
				(width 0.1)
				(type default)
			)
			(layer "B.Fab")
		)
		(fp_line
			(start 0.12065 -0.2794)
			(end -0.12065 -0.2794)
			(stroke
				(width 0.1)
				(type default)
			)
			(layer "B.Fab")
		)
		(fp_line
			(start -0.67945 -0.3048)
			(end -0.67945 0.3048)
			(stroke
				(width 0.1)
				(type default)
			)
			(layer "B.Fab")
		)
		(fp_line
			(start -0.12065 -0.3048)
			(end -0.67945 -0.3048)
			(stroke
				(width 0.1)
				(type default)
			)
			(layer "B.Fab")
		)
		(fp_line
			(start 0.12065 -0.305054)
			(end 0.12065 -0.2794)
			(stroke
				(width 0.1)
				(type default)
			)
			(layer "B.Fab")
		)
		(fp_line
			(start 0.67945 -0.305054)
			(end 0.12065 -0.305054)
			(stroke
				(width 0.1)
				(type default)
			)
			(layer "B.Fab")
		)
		(pad "1" smd circle
			(at 0.40005 0 90)
			(size 0 0)
			(layers "B.Cu" "B.Mask" "B.Paste")
			(net "PVCCFA_EHV_FIVRA_CPU0_PVCC2")
		)
		(pad "2" smd circle
			(at -0.40005 0 90)
			(size 0 0)
			(layers "B.Cu" "B.Mask" "B.Paste")
			(net "PVCCFA_EHV_FIVRA_CPU0_VDD2")
		)
	)
	(footprint ""
		(layer "B.Cu")
		(at 215.840818 -315.334904 -90)
		(property "Reference" "R947"
			(at 0 0 90)
			(layer "B.SilkS")
			(hide yes)
			(effects
				(font
					(size 1.27 1.27)
				)
				(justify mirror)
			)
		)
		(property "Value" ""
			(at 0 0 90)
			(layer "B.Fab")
			(effects
				(font
					(size 1.27 1.27)
				)
				(justify mirror)
			)
		)
		(duplicate_pad_numbers_are_jumpers no)
		(fp_line
			(start -0.7874 0.4064)
			(end 0.7874 0.4064)
			(stroke
				(width 0.1524)
				(type default)
			)
			(layer "B.SilkS")
		)
		(fp_line
			(start 0.7874 0.4064)
			(end 0.7874 -0.4064)
			(stroke
				(width 0.1524)
				(type default)
			)
			(layer "B.SilkS")
		)
		(fp_line
			(start -0.7874 -0.4064)
			(end -0.7874 0.4064)
			(stroke
				(width 0.1524)
				(type default)
			)
			(layer "B.SilkS")
		)
		(fp_line
			(start 0.7874 -0.4064)
			(end -0.7874 -0.4064)
			(stroke
				(width 0.1524)
				(type default)
			)
			(layer "B.SilkS")
		)
		(fp_line
			(start -0.67945 0.3048)
			(end -0.120396 0.3048)
			(stroke
				(width 0.1)
				(type default)
			)
			(layer "B.Fab")
		)
		(fp_line
			(start -0.120396 0.3048)
			(end -0.120396 0.2794)
			(stroke
				(width 0.1)
				(type default)
			)
			(layer "B.Fab")
		)
		(fp_line
			(start 0.12065 0.3048)
			(end 0.67945 0.3048)
			(stroke
				(width 0.1)
				(type default)
			)
			(layer "B.Fab")
		)
		(fp_line
			(start 0.67945 0.3048)
			(end 0.67945 -0.305054)
			(stroke
				(width 0.1)
				(type default)
			)
			(layer "B.Fab")
		)
		(fp_line
			(start -0.120396 0.2794)
			(end 0.12065 0.2794)
			(stroke
				(width 0.1)
				(type default)
			)
			(layer "B.Fab")
		)
		(fp_line
			(start 0.12065 0.2794)
			(end 0.12065 0.3048)
			(stroke
				(width 0.1)
				(type default)
			)
			(layer "B.Fab")
		)
		(fp_line
			(start -0.12065 -0.2794)
			(end -0.12065 -0.3048)
			(stroke
				(width 0.1)
				(type default)
			)
			(layer "B.Fab")
		)
		(fp_line
			(start 0.12065 -0.2794)
			(end -0.12065 -0.2794)
			(stroke
				(width 0.1)
				(type default)
			)
			(layer "B.Fab")
		)
		(fp_line
			(start -0.67945 -0.3048)
			(end -0.67945 0.3048)
			(stroke
				(width 0.1)
				(type default)
			)
			(layer "B.Fab")
		)
		(fp_line
			(start -0.12065 -0.3048)
			(end -0.67945 -0.3048)
			(stroke
				(width 0.1)
				(type default)
			)
			(layer "B.Fab")
		)
		(fp_line
			(start 0.12065 -0.305054)
			(end 0.12065 -0.2794)
			(stroke
				(width 0.1)
				(type default)
			)
			(layer "B.Fab")
		)
		(fp_line
			(start 0.67945 -0.305054)
			(end 0.12065 -0.305054)
			(stroke
				(width 0.1)
				(type default)
			)
			(layer "B.Fab")
		)
		(pad "1" smd circle
			(at 0.40005 0 90)
			(size 0 0)
			(layers "B.Cu" "B.Mask" "B.Paste")
			(net "P3V3_AUX")
		)
		(pad "2" smd circle
			(at -0.40005 0 90)
			(size 0 0)
			(layers "B.Cu" "B.Mask" "B.Paste")
			(net "PWRGD_FAIL_CPU1_GH_R1")
		)
	)
	(footprint ""
		(layer "B.Cu")
		(at 105.726738 -241.19459 90)
		(property "Reference" "C483"
			(at 0 0 90)
			(layer "B.SilkS")
			(hide yes)
			(effects
				(font
					(size 1.27 1.27)
				)
				(justify mirror)
			)
		)
		(property "Value" ""
			(at 0 0 90)
			(layer "B.Fab")
			(effects
				(font
					(size 1.27 1.27)
				)
				(justify mirror)
			)
		)
		(duplicate_pad_numbers_are_jumpers no)
		(fp_line
			(start 1.524 -0.762)
			(end -1.524 -0.762)
			(stroke
				(width 0.1524)
				(type default)
			)
			(layer "B.SilkS")
		)
		(fp_line
			(start -1.524 -0.762)
			(end -1.524 0.762)
			(stroke
				(width 0.1524)
				(type default)
			)
			(layer "B.SilkS")
		)
		(fp_line
			(start 1.524 0.762)
			(end 1.524 -0.762)
			(stroke
				(width 0.1524)
				(type default)
			)
			(layer "B.SilkS")
		)
		(fp_line
			(start -1.524 0.762)
			(end 1.524 0.762)
			(stroke
				(width 0.1524)
				(type default)
			)
			(layer "B.SilkS")
		)
		(fp_line
			(start 1.1049 -0.724916)
			(end 1.1049 0.724916)
			(stroke
				(width 0.1)
				(type default)
			)
			(layer "B.Fab")
		)
		(fp_line
			(start -1.1049 -0.724916)
			(end 1.1049 -0.724916)
			(stroke
				(width 0.1)
				(type default)
			)
			(layer "B.Fab")
		)
		(fp_line
			(start 1.1049 0.724916)
			(end -1.1049 0.724916)
			(stroke
				(width 0.1)
				(type default)
			)
			(layer "B.Fab")
		)
		(fp_line
			(start -1.1049 0.724916)
			(end -1.1049 -0.724916)
			(stroke
				(width 0.1)
				(type default)
			)
			(layer "B.Fab")
		)
		(pad "1" smd rect
			(at 0.889 0 90)
			(size 1.016 1.27)
			(layers "B.Cu" "B.Mask" "B.Paste")
			(net "PVCCIN_CPU1")
		)
		(pad "2" smd rect
			(at -0.889 0 90)
			(size 1.016 1.27)
			(layers "B.Cu" "B.Mask" "B.Paste")
			(net "GND")
		)
	)
	(footprint ""
		(layer "B.Cu")
		(at 111.82858 -411.676088 -90)
		(property "Reference" "C2339"
			(at 0 0 90)
			(layer "B.SilkS")
			(hide yes)
			(effects
				(font
					(size 1.27 1.27)
				)
				(justify mirror)
			)
		)
		(property "Value" ""
			(at 0 0 90)
			(layer "B.Fab")
			(effects
				(font
					(size 1.27 1.27)
				)
				(justify mirror)
			)
		)
		(duplicate_pad_numbers_are_jumpers no)
		(fp_line
			(start -0.7874 0.4064)
			(end 0.7874 0.4064)
			(stroke
				(width 0.1524)
				(type default)
			)
			(layer "B.SilkS")
		)
		(fp_line
			(start 0.7874 0.4064)
			(end 0.7874 -0.4064)
			(stroke
				(width 0.1524)
				(type default)
			)
			(layer "B.SilkS")
		)
		(fp_line
			(start -0.7874 -0.4064)
			(end -0.7874 0.4064)
			(stroke
				(width 0.1524)
				(type default)
			)
			(layer "B.SilkS")
		)
		(fp_line
			(start 0.7874 -0.4064)
			(end -0.7874 -0.4064)
			(stroke
				(width 0.1524)
				(type default)
			)
			(layer "B.SilkS")
		)
		(fp_line
			(start -0.67945 0.3048)
			(end -0.120396 0.3048)
			(stroke
				(width 0.1)
				(type default)
			)
			(layer "B.Fab")
		)
		(fp_line
			(start -0.120396 0.3048)
			(end -0.120396 0.2794)
			(stroke
				(width 0.1)
				(type default)
			)
			(layer "B.Fab")
		)
		(fp_line
			(start 0.12065 0.3048)
			(end 0.67945 0.3048)
			(stroke
				(width 0.1)
				(type default)
			)
			(layer "B.Fab")
		)
		(fp_line
			(start 0.67945 0.3048)
			(end 0.67945 -0.305054)
			(stroke
				(width 0.1)
				(type default)
			)
			(layer "B.Fab")
		)
		(fp_line
			(start -0.120396 0.2794)
			(end 0.12065 0.2794)
			(stroke
				(width 0.1)
				(type default)
			)
			(layer "B.Fab")
		)
		(fp_line
			(start 0.12065 0.2794)
			(end 0.12065 0.3048)
			(stroke
				(width 0.1)
				(type default)
			)
			(layer "B.Fab")
		)
		(fp_line
			(start -0.12065 -0.2794)
			(end -0.12065 -0.3048)
			(stroke
				(width 0.1)
				(type default)
			)
			(layer "B.Fab")
		)
		(fp_line
			(start 0.12065 -0.2794)
			(end -0.12065 -0.2794)
			(stroke
				(width 0.1)
				(type default)
			)
			(layer "B.Fab")
		)
		(fp_line
			(start -0.67945 -0.3048)
			(end -0.67945 0.3048)
			(stroke
				(width 0.1)
				(type default)
			)
			(layer "B.Fab")
		)
		(fp_line
			(start -0.12065 -0.3048)
			(end -0.67945 -0.3048)
			(stroke
				(width 0.1)
				(type default)
			)
			(layer "B.Fab")
		)
		(fp_line
			(start 0.12065 -0.305054)
			(end 0.12065 -0.2794)
			(stroke
				(width 0.1)
				(type default)
			)
			(layer "B.Fab")
		)
		(fp_line
			(start 0.67945 -0.305054)
			(end 0.12065 -0.305054)
			(stroke
				(width 0.1)
				(type default)
			)
			(layer "B.Fab")
		)
		(pad "1" smd circle
			(at 0.40005 0 90)
			(size 0 0)
			(layers "B.Cu" "B.Mask" "B.Paste")
			(net "P3V3_9ZXL045_VDD")
		)
		(pad "2" smd circle
			(at -0.40005 0 90)
			(size 0 0)
			(layers "B.Cu" "B.Mask" "B.Paste")
			(net "GND")
		)
	)
	(footprint ""
		(layer "B.Cu")
		(at 179.352448 -403.271482)
		(property "Reference" "PC2191"
			(at 0 0 0)
			(layer "B.SilkS")
			(hide yes)
			(effects
				(font
					(size 1.27 1.27)
				)
				(justify mirror)
			)
		)
		(property "Value" ""
			(at 0 0 0)
			(layer "B.Fab")
			(effects
				(font
					(size 1.27 1.27)
				)
				(justify mirror)
			)
		)
		(duplicate_pad_numbers_are_jumpers no)
		(fp_line
			(start -0.7874 -0.4064)
			(end -0.7874 0.4064)
			(stroke
				(width 0.1524)
				(type default)
			)
			(layer "B.SilkS")
		)
		(fp_line
			(start -0.7874 0.4064)
			(end 0.7874 0.4064)
			(stroke
				(width 0.1524)
				(type default)
			)
			(layer "B.SilkS")
		)
		(fp_line
			(start 0.7874 -0.4064)
			(end -0.7874 -0.4064)
			(stroke
				(width 0.1524)
				(type default)
			)
			(layer "B.SilkS")
		)
		(fp_line
			(start 0.7874 0.4064)
			(end 0.7874 -0.4064)
			(stroke
				(width 0.1524)
				(type default)
			)
			(layer "B.SilkS")
		)
		(fp_line
			(start -0.67945 -0.3048)
			(end -0.67945 0.3048)
			(stroke
				(width 0.1)
				(type default)
			)
			(layer "B.Fab")
		)
		(fp_line
			(start -0.67945 0.3048)
			(end -0.120396 0.3048)
			(stroke
				(width 0.1)
				(type default)
			)
			(layer "B.Fab")
		)
		(fp_line
			(start -0.12065 -0.3048)
			(end -0.67945 -0.3048)
			(stroke
				(width 0.1)
				(type default)
			)
			(layer "B.Fab")
		)
		(fp_line
			(start -0.12065 -0.2794)
			(end -0.12065 -0.3048)
			(stroke
				(width 0.1)
				(type default)
			)
			(layer "B.Fab")
		)
		(fp_line
			(start -0.120396 0.2794)
			(end 0.12065 0.2794)
			(stroke
				(width 0.1)
				(type default)
			)
			(layer "B.Fab")
		)
		(fp_line
			(start -0.120396 0.3048)
			(end -0.120396 0.2794)
			(stroke
				(width 0.1)
				(type default)
			)
			(layer "B.Fab")
		)
		(fp_line
			(start 0.12065 -0.305054)
			(end 0.12065 -0.2794)
			(stroke
				(width 0.1)
				(type default)
			)
			(layer "B.Fab")
		)
		(fp_line
			(start 0.12065 -0.2794)
			(end -0.12065 -0.2794)
			(stroke
				(width 0.1)
				(type default)
			)
			(layer "B.Fab")
		)
		(fp_line
			(start 0.12065 0.2794)
			(end 0.12065 0.3048)
			(stroke
				(width 0.1)
				(type default)
			)
			(layer "B.Fab")
		)
		(fp_line
			(start 0.12065 0.3048)
			(end 0.67945 0.3048)
			(stroke
				(width 0.1)
				(type default)
			)
			(layer "B.Fab")
		)
		(fp_line
			(start 0.67945 -0.305054)
			(end 0.12065 -0.305054)
			(stroke
				(width 0.1)
				(type default)
			)
			(layer "B.Fab")
		)
		(fp_line
			(start 0.67945 0.3048)
			(end 0.67945 -0.305054)
			(stroke
				(width 0.1)
				(type default)
			)
			(layer "B.Fab")
		)
		(pad "1" smd circle
			(at 0.40005 0 180)
			(size 0 0)
			(layers "B.Cu" "B.Mask" "B.Paste")
			(net "HSC_SS")
		)
		(pad "2" smd circle
			(at -0.40005 0 180)
			(size 0 0)
			(layers "B.Cu" "B.Mask" "B.Paste")
			(net "AGND_HSC")
		)
	)
	(footprint ""
		(layer "B.Cu")
		(at 400.686778 -190.77559 90)
		(property "Reference" "R181"
			(at 0 0 90)
			(layer "B.SilkS")
			(hide yes)
			(effects
				(font
					(size 1.27 1.27)
				)
				(justify mirror)
			)
		)
		(property "Value" ""
			(at 0 0 90)
			(layer "B.Fab")
			(effects
				(font
					(size 1.27 1.27)
				)
				(justify mirror)
			)
		)
		(duplicate_pad_numbers_are_jumpers no)
		(fp_line
			(start 0.7874 -0.4064)
			(end -0.7874 -0.4064)
			(stroke
				(width 0.1524)
				(type default)
			)
			(layer "B.SilkS")
		)
		(fp_line
			(start -0.7874 -0.4064)
			(end -0.7874 0.4064)
			(stroke
				(width 0.1524)
				(type default)
			)
			(layer "B.SilkS")
		)
		(fp_line
			(start 0.7874 0.4064)
			(end 0.7874 -0.4064)
			(stroke
				(width 0.1524)
				(type default)
			)
			(layer "B.SilkS")
		)
		(fp_line
			(start -0.7874 0.4064)
			(end 0.7874 0.4064)
			(stroke
				(width 0.1524)
				(type default)
			)
			(layer "B.SilkS")
		)
		(fp_line
			(start 0.67945 -0.305054)
			(end 0.12065 -0.305054)
			(stroke
				(width 0.1)
				(type default)
			)
			(layer "B.Fab")
		)
		(fp_line
			(start 0.12065 -0.305054)
			(end 0.12065 -0.2794)
			(stroke
				(width 0.1)
				(type default)
			)
			(layer "B.Fab")
		)
		(fp_line
			(start -0.12065 -0.3048)
			(end -0.67945 -0.3048)
			(stroke
				(width 0.1)
				(type default)
			)
			(layer "B.Fab")
		)
		(fp_line
			(start -0.67945 -0.3048)
			(end -0.67945 0.3048)
			(stroke
				(width 0.1)
				(type default)
			)
			(layer "B.Fab")
		)
		(fp_line
			(start 0.12065 -0.2794)
			(end -0.12065 -0.2794)
			(stroke
				(width 0.1)
				(type default)
			)
			(layer "B.Fab")
		)
		(fp_line
			(start -0.12065 -0.2794)
			(end -0.12065 -0.3048)
			(stroke
				(width 0.1)
				(type default)
			)
			(layer "B.Fab")
		)
		(fp_line
			(start 0.12065 0.2794)
			(end 0.12065 0.3048)
			(stroke
				(width 0.1)
				(type default)
			)
			(layer "B.Fab")
		)
		(fp_line
			(start -0.120396 0.2794)
			(end 0.12065 0.2794)
			(stroke
				(width 0.1)
				(type default)
			)
			(layer "B.Fab")
		)
		(fp_line
			(start 0.67945 0.3048)
			(end 0.67945 -0.305054)
			(stroke
				(width 0.1)
				(type default)
			)
			(layer "B.Fab")
		)
		(fp_line
			(start 0.12065 0.3048)
			(end 0.67945 0.3048)
			(stroke
				(width 0.1)
				(type default)
			)
			(layer "B.Fab")
		)
		(fp_line
			(start -0.120396 0.3048)
			(end -0.120396 0.2794)
			(stroke
				(width 0.1)
				(type default)
			)
			(layer "B.Fab")
		)
		(fp_line
			(start -0.67945 0.3048)
			(end -0.120396 0.3048)
			(stroke
				(width 0.1)
				(type default)
			)
			(layer "B.Fab")
		)
		(pad "1" smd circle
			(at 0.40005 0 270)
			(size 0 0)
			(layers "B.Cu" "B.Mask" "B.Paste")
			(net "PWRGD_DRAMPWRGD_CPU0_GH_LVC1_R2")
		)
		(pad "2" smd circle
			(at -0.40005 0 270)
			(size 0 0)
			(layers "B.Cu" "B.Mask" "B.Paste")
			(net "PVCCD_HV_CPU0")
		)
	)
)
